(kicad_pcb
	(version 20260206)
	(generator "pcbnew")
	(generator_version "10.0")
	(general
		(thickness 1.6)
		(legacy_teardrops no)
	)
	(paper "A4")
	(title_block
		(title "04192023_DAF0TMB3IC0_F0TG_MB_C_brd_V02_OCP.brd")
		(comment 1 "Grand Teton / footprint 3166 of 8354 (J41), pads 108-175 of 175")
	)
	(layers
		(0 "F.Cu" signal "TOP")
		(4 "In1.Cu" signal "GND")
		(6 "In2.Cu" signal "IN1")
		(8 "In3.Cu" signal "GND1")
		(10 "In4.Cu" signal "IN2")
		(12 "In5.Cu" signal "GND2")
		(14 "In6.Cu" signal "IN3")
		(16 "In7.Cu" signal "GND3")
		(18 "In8.Cu" signal "VCC")
		(20 "In9.Cu" signal "VCC1")
		(22 "In10.Cu" signal "GND4")
		(24 "In11.Cu" signal "IN4")
		(26 "In12.Cu" signal "GND5")
		(28 "In13.Cu" signal "IN5")
		(30 "In14.Cu" signal "GND6")
		(32 "In15.Cu" signal "IN6")
		(34 "In16.Cu" signal "GND7")
		(2 "B.Cu" signal "BOTTOM")
		(9 "F.Adhes" user "F.Adhesive")
		(11 "B.Adhes" user "B.Adhesive")
		(13 "F.Paste" user "Package Geometry/Pastemask Top")
		(15 "B.Paste" user "Package Geometry/Pastemask Bottom")
		(5 "F.SilkS" user "Ref Des/Silkscreen Top")
		(7 "B.SilkS" user "Ref Des/Silkscreen Bottom")
		(1 "F.Mask" user "Board Geometry/Soldermask Top")
		(3 "B.Mask" user "Board Geometry/Soldermask Bottom")
		(17 "Dwgs.User" user "User.Drawings")
		(19 "Cmts.User" user "User.Comments")
		(21 "Eco1.User" user "User.Eco1")
		(23 "Eco2.User" user "User.Eco2")
		(25 "Edge.Cuts" user "Board Geometry/Outline")
		(27 "Margin" user)
		(31 "F.CrtYd" user "Package Geometry/Place Bound Top")
		(29 "B.CrtYd" user "Package Geometry/Place Bound Bottom")
		(35 "F.Fab" user "Ref Des/Assembly Top")
		(33 "B.Fab" user "Ref Des/Assembly Bottom")
	)
	(footprint ""
		(layer "F.Cu")
		(at 160.402016 -10.849864 -90)
		(property "Reference" "J41"
			(at -8.65886 -21.78558 0)
			(unlocked yes)
			(layer "F.SilkS")
			(effects
				(font
					(size 0.7874 0.5842)
					(thickness 0.1524)
				)
				(justify left)
			)
		)
		(property "Value" ""
			(at 0 0 270)
			(layer "F.Fab")
			(effects
				(font
					(size 1.27 1.27)
				)
			)
		)
		(duplicate_pad_numbers_are_jumpers no)
		(pad "B36" smd rect
			(at -5.700014 5.945124 180)
			(size 0.381 1.4478)
			(layers "F.Cu" "F.Mask" "F.Paste")
			(net "SGPIO_SCM_DI_R_<1>")
		)
		(pad "B37" smd rect
			(at -5.700014 6.545072 180)
			(size 0.381 1.4478)
			(layers "F.Cu" "F.Mask" "F.Paste")
			(net "SGPIO_SCM_LD_R_<1>")
		)
		(pad "B38" smd rect
			(at -5.700014 7.14502 180)
			(size 0.381 1.4478)
			(layers "F.Cu" "F.Mask" "F.Paste")
			(net "GND")
		)
		(pad "B39" smd rect
			(at -5.700014 7.744968 180)
			(size 0.381 1.4478)
			(layers "F.Cu" "F.Mask" "F.Paste")
			(net "SGPIO_SCM_RESET_R_N")
		)
		(pad "B40" smd rect
			(at -5.700014 8.344916 180)
			(size 0.381 1.4478)
			(layers "F.Cu" "F.Mask" "F.Paste")
			(net "SGPIO_SCM_INTR_R1_N")
		)
		(pad "B41" smd rect
			(at -5.700014 8.945118 180)
			(size 0.381 1.4478)
			(layers "F.Cu" "F.Mask" "F.Paste")
			(net "SCM_VDD_RTC")
		)
		(pad "B42" smd rect
			(at -5.700014 9.545066 180)
			(size 0.381 1.4478)
			(layers "F.Cu" "F.Mask" "F.Paste")
			(net "FM_AC_PWR_BTN_N")
		)
		(pad "B43" smd rect
			(at -5.700014 14.454886 180)
			(size 0.381 1.4478)
			(layers "F.Cu" "F.Mask" "F.Paste")
			(net "TP_SPI_2_PLD_CLK")
		)
		(pad "B44" smd rect
			(at -5.700014 15.055088 180)
			(size 0.381 1.4478)
			(layers "F.Cu" "F.Mask" "F.Paste")
			(net "TP_SPI_2_PLD_CS_N")
		)
		(pad "B45" smd rect
			(at -5.700014 15.655036 180)
			(size 0.381 1.4478)
			(layers "F.Cu" "F.Mask" "F.Paste")
			(net "TP_SPI_2_PLD_IO0")
		)
		(pad "B46" smd rect
			(at -5.700014 16.254984 180)
			(size 0.381 1.4478)
			(layers "F.Cu" "F.Mask" "F.Paste")
			(net "TP_SPI_2_PLD_IO1")
		)
		(pad "B47" smd rect
			(at -5.700014 16.854932 180)
			(size 0.381 1.4478)
			(layers "F.Cu" "F.Mask" "F.Paste")
			(net "TP_SPI_2_PLD_IO2")
		)
		(pad "B48" smd rect
			(at -5.700014 17.45488 180)
			(size 0.381 1.4478)
			(layers "F.Cu" "F.Mask" "F.Paste")
			(net "TP_SPI_2_PLD_IO3")
		)
		(pad "B49" smd rect
			(at -5.700014 18.055082 180)
			(size 0.381 1.4478)
			(layers "F.Cu" "F.Mask" "F.Paste")
			(net "GND")
		)
		(pad "B50" smd rect
			(at -5.700014 18.65503 180)
			(size 0.381 1.4478)
			(layers "F.Cu" "F.Mask" "F.Paste")
			(net "USB2_HOST_BMC_B_DP")
		)
		(pad "B51" smd rect
			(at -5.700014 19.254978 180)
			(size 0.381 1.4478)
			(layers "F.Cu" "F.Mask" "F.Paste")
			(net "USB2_HOST_BMC_B_DN")
		)
		(pad "B52" smd rect
			(at -5.700014 19.854926 180)
			(size 0.381 1.4478)
			(layers "F.Cu" "F.Mask" "F.Paste")
			(net "GND")
		)
		(pad "B53" smd rect
			(at -5.700014 20.455128 180)
			(size 0.381 1.4478)
			(layers "F.Cu" "F.Mask" "F.Paste")
			(net "USB2_CPU0_P1_DP")
		)
		(pad "B54" smd rect
			(at -5.700014 21.055076 180)
			(size 0.381 1.4478)
			(layers "F.Cu" "F.Mask" "F.Paste")
			(net "USB2_CPU0_P1_DN")
		)
		(pad "B55" smd rect
			(at -5.700014 21.655024 180)
			(size 0.381 1.4478)
			(layers "F.Cu" "F.Mask" "F.Paste")
			(net "GND")
		)
		(pad "B56" smd rect
			(at -5.700014 22.254972 180)
			(size 0.381 1.4478)
			(layers "F.Cu" "F.Mask" "F.Paste")
			(net "USB2_HUB_EXT_DP")
		)
		(pad "B57" smd rect
			(at -5.700014 22.85492 180)
			(size 0.381 1.4478)
			(layers "F.Cu" "F.Mask" "F.Paste")
			(net "USB2_HUB_EXT_DN")
		)
		(pad "B58" smd rect
			(at -5.700014 23.455122 180)
			(size 0.381 1.4478)
			(layers "F.Cu" "F.Mask" "F.Paste")
			(net "GND")
		)
		(pad "B59" smd rect
			(at -5.700014 24.05507 180)
			(size 0.381 1.4478)
			(layers "F.Cu" "F.Mask" "F.Paste")
			(net "USB3_CPU0_BMC_TX_BUF_C_DP")
		)
		(pad "B60" smd rect
			(at -5.700014 24.655018 180)
			(size 0.381 1.4478)
			(layers "F.Cu" "F.Mask" "F.Paste")
			(net "USB3_CPU0_BMC_TX_BUF_C_DN")
		)
		(pad "B61" smd rect
			(at -5.700014 25.254966 180)
			(size 0.381 1.4478)
			(layers "F.Cu" "F.Mask" "F.Paste")
			(net "GND")
		)
		(pad "B62" smd rect
			(at -5.700014 25.854914 180)
			(size 0.381 1.4478)
			(layers "F.Cu" "F.Mask" "F.Paste")
			(net "TP_PCIE_TXP<1>")
		)
		(pad "B63" smd rect
			(at -5.700014 26.455116 180)
			(size 0.381 1.4478)
			(layers "F.Cu" "F.Mask" "F.Paste")
			(net "TP_PCIE_TXN<1>")
		)
		(pad "B64" smd rect
			(at -5.700014 27.055064 180)
			(size 0.381 1.4478)
			(layers "F.Cu" "F.Mask" "F.Paste")
			(net "GND")
		)
		(pad "B65" smd rect
			(at -5.700014 27.655012 180)
			(size 0.381 1.4478)
			(layers "F.Cu" "F.Mask" "F.Paste")
			(net "P2E_MB_BMC_TX_C_DP<0>")
		)
		(pad "B66" smd rect
			(at -5.700014 28.25496 180)
			(size 0.381 1.4478)
			(layers "F.Cu" "F.Mask" "F.Paste")
			(net "P2E_MB_BMC_TX_C_DN<0>")
		)
		(pad "B67" smd rect
			(at -5.700014 28.854908 180)
			(size 0.381 1.4478)
			(layers "F.Cu" "F.Mask" "F.Paste")
			(net "GND")
		)
		(pad "B68" smd rect
			(at -5.700014 29.45511 180)
			(size 0.381 1.4478)
			(layers "F.Cu" "F.Mask" "F.Paste")
			(net "TP_PCIE_TXP<3>")
		)
		(pad "B69" smd rect
			(at -5.700014 30.055058 180)
			(size 0.381 1.4478)
			(layers "F.Cu" "F.Mask" "F.Paste")
			(net "TP_BEEP_LED")
		)
		(pad "B70" smd rect
			(at -5.700014 30.655006 180)
			(size 0.381 1.4478)
			(layers "F.Cu" "F.Mask" "F.Paste")
			(net "GND")
		)
		(pad "G1" thru_hole circle
			(at 2.400046 -32.759904 180)
			(size 1.6256 1.6256)
			(drill 1.1176)
			(layers "*.Cu" "*.Mask")
			(remove_unused_layers no)
			(net "GND")
			(clearance 0)
		)
		(pad "G2" thru_hole circle
			(at 2.400046 -20.379944 180)
			(size 1.6256 1.6256)
			(drill 1.1176)
			(layers "*.Cu" "*.Mask")
			(remove_unused_layers no)
			(net "GND")
			(clearance 0)
		)
		(pad "G3" thru_hole circle
			(at 2.400046 0 180)
			(size 1.6256 1.6256)
			(drill 1.1176)
			(layers "*.Cu" "*.Mask")
			(remove_unused_layers no)
			(net "GND")
			(clearance 0)
		)
		(pad "G4" thru_hole circle
			(at 2.400046 12.5349 180)
			(size 1.6256 1.6256)
			(drill 1.1176)
			(layers "*.Cu" "*.Mask")
			(remove_unused_layers no)
			(net "GND")
			(clearance 0)
		)
		(pad "G5" thru_hole circle
			(at 2.400046 32.759904 180)
			(size 1.6256 1.6256)
			(drill 1.1176)
			(layers "*.Cu" "*.Mask")
			(remove_unused_layers no)
			(net "GND")
			(clearance 0)
		)
		(pad "OA1" smd rect
			(at -2.750058 -30.660086 180)
			(size 0.381 1.4478)
			(layers "F.Cu" "F.Mask" "F.Paste")
			(net "P12V_SCM")
		)
		(pad "OA2" smd rect
			(at -2.750058 -30.059884 180)
			(size 0.381 1.4478)
			(layers "F.Cu" "F.Mask" "F.Paste")
			(net "P12V_SCM")
		)
		(pad "OA3" smd rect
			(at -2.750058 -29.459936 180)
			(size 0.381 1.4478)
			(layers "F.Cu" "F.Mask" "F.Paste")
			(net "GND")
		)
		(pad "OA4" smd rect
			(at -2.750058 -28.859988 180)
			(size 0.381 1.4478)
			(layers "F.Cu" "F.Mask" "F.Paste")
			(net "GND")
		)
		(pad "OA5" smd rect
			(at -2.750058 -28.26004 180)
			(size 0.381 1.4478)
			(layers "F.Cu" "F.Mask" "F.Paste")
			(net "I3C_SCM_0_SCL")
		)
		(pad "OA6" smd rect
			(at -2.750058 -27.660092 180)
			(size 0.381 1.4478)
			(layers "F.Cu" "F.Mask" "F.Paste")
			(net "I3C_SCM_0_SDA")
		)
		(pad "OA7" smd rect
			(at -2.750058 -27.05989 180)
			(size 0.381 1.4478)
			(layers "F.Cu" "F.Mask" "F.Paste")
			(net "I3C_SCM_1_SCL")
		)
		(pad "OA8" smd rect
			(at -2.750058 -26.459942 180)
			(size 0.381 1.4478)
			(layers "F.Cu" "F.Mask" "F.Paste")
			(net "I3C_SCM_1_SDA")
		)
		(pad "OA9" smd rect
			(at -2.750058 -25.859994 180)
			(size 0.381 1.4478)
			(layers "F.Cu" "F.Mask" "F.Paste")
			(net "I3C_SCM_2_SCL")
		)
		(pad "OA10" smd rect
			(at -2.750058 -25.260046 180)
			(size 0.381 1.4478)
			(layers "F.Cu" "F.Mask" "F.Paste")
			(net "I3C_SCM_2_SDA")
		)
		(pad "OA11" smd rect
			(at -2.750058 -24.660098 180)
			(size 0.381 1.4478)
			(layers "F.Cu" "F.Mask" "F.Paste")
			(net "I3C_SCM_3_SCL")
		)
		(pad "OA12" smd rect
			(at -2.750058 -24.059896 180)
			(size 0.381 1.4478)
			(layers "F.Cu" "F.Mask" "F.Paste")
			(net "I3C_SCM_3_SDA")
		)
		(pad "OA13" smd rect
			(at -2.750058 -23.459948 180)
			(size 0.381 1.4478)
			(layers "F.Cu" "F.Mask" "F.Paste")
			(net "GND")
		)
		(pad "OA14" smd rect
			(at -2.750058 -22.86 180)
			(size 0.381 1.4478)
			(layers "F.Cu" "F.Mask" "F.Paste")
			(net "VIRTUAL_RESEAT")
		)
		(pad "OB1" smd rect
			(at -5.700014 -30.660086 180)
			(size 0.381 1.4478)
			(layers "F.Cu" "F.Mask" "F.Paste")
			(net "P12V_SCM")
		)
		(pad "OB2" smd rect
			(at -5.700014 -30.059884 180)
			(size 0.381 1.4478)
			(layers "F.Cu" "F.Mask" "F.Paste")
			(net "P12V_SCM")
		)
		(pad "OB3" smd rect
			(at -5.700014 -29.459936 180)
			(size 0.381 1.4478)
			(layers "F.Cu" "F.Mask" "F.Paste")
			(net "PRSNT0_N")
		)
		(pad "OB4" smd rect
			(at -5.700014 -28.859988 180)
			(size 0.381 1.4478)
			(layers "F.Cu" "F.Mask" "F.Paste")
			(net "GND")
		)
		(pad "OB5" smd rect
			(at -5.700014 -28.26004 180)
			(size 0.381 1.4478)
			(layers "F.Cu" "F.Mask" "F.Paste")
			(net "UART_BMC_BIC_TX")
		)
		(pad "OB6" smd rect
			(at -5.700014 -27.660092 180)
			(size 0.381 1.4478)
			(layers "F.Cu" "F.Mask" "F.Paste")
			(net "UART_BMC_BIC_BUF_RX")
		)
		(pad "OB7" smd rect
			(at -5.700014 -27.05989 180)
			(size 0.381 1.4478)
			(layers "F.Cu" "F.Mask" "F.Paste")
			(net "GND")
		)
		(pad "OB8" smd rect
			(at -5.700014 -26.459942 180)
			(size 0.381 1.4478)
			(layers "F.Cu" "F.Mask" "F.Paste")
			(net "UART_CPU0_SCM_LVC3_UART1_RX")
		)
		(pad "OB9" smd rect
			(at -5.700014 -25.859994 180)
			(size 0.381 1.4478)
			(layers "F.Cu" "F.Mask" "F.Paste")
			(net "UART_CPU0_SCM_LVC3_UART1_R1_TX")
		)
		(pad "OB10" smd rect
			(at -5.700014 -25.260046 180)
			(size 0.381 1.4478)
			(layers "F.Cu" "F.Mask" "F.Paste")
			(net "GND")
		)
		(pad "OB11" smd rect
			(at -5.700014 -24.660098 180)
			(size 0.381 1.4478)
			(layers "F.Cu" "F.Mask" "F.Paste")
			(net "RST_SRST_PLD_BMC_N")
		)
		(pad "OB12" smd rect
			(at -5.700014 -24.059896 180)
			(size 0.381 1.4478)
			(layers "F.Cu" "F.Mask" "F.Paste")
			(net "SPI_CPU0_LVC3_TPM_CS_N")
		)
		(pad "OB13" smd rect
			(at -5.700014 -23.459948 180)
			(size 0.381 1.4478)
			(layers "F.Cu" "F.Mask" "F.Paste")
			(net "FPGA_IO3V3_RSVD_1")
		)
		(pad "OB14" smd rect
			(at -5.700014 -22.86 180)
			(size 0.381 1.4478)
			(layers "F.Cu" "F.Mask" "F.Paste")
			(net "FM_SOL_UART_CH_SEL_R")
		)
	)
)
